(kicad_pcb
	(version 20260206)
	(generator "pcbnew")
	(generator_version "10.0")
	(general
		(thickness 1.6)
		(legacy_teardrops no)
	)
	(paper "A4")
	(title_block
		(title "12092022_DA0F0TMDCD0_F0T_Management_Board_D_brd_V3_OCP.brd")
		(comment 1 "Grand Teton / footprints 1147-1152 of 1440")
	)
	(layers
		(0 "F.Cu" signal "TOP")
		(4 "In1.Cu" signal "GND")
		(6 "In2.Cu" signal "IN1")
		(8 "In3.Cu" signal "GND1")
		(10 "In4.Cu" signal "IN2")
		(12 "In5.Cu" signal "VCC")
		(14 "In6.Cu" signal "VCC1")
		(16 "In7.Cu" signal "IN3")
		(18 "In8.Cu" signal "GND2")
		(20 "In9.Cu" signal "IN4")
		(22 "In10.Cu" signal "GND3")
		(2 "B.Cu" signal "BOTTOM")
		(9 "F.Adhes" user "F.Adhesive")
		(11 "B.Adhes" user "B.Adhesive")
		(13 "F.Paste" user "Package Geometry/Pastemask Top")
		(15 "B.Paste" user "Package Geometry/Pastemask Bottom")
		(5 "F.SilkS" user "Ref Des/Silkscreen Top")
		(7 "B.SilkS" user "Ref Des/Silkscreen Bottom")
		(1 "F.Mask" user "Board Geometry/Soldermask Top")
		(3 "B.Mask" user "Board Geometry/Soldermask Bottom")
		(17 "Dwgs.User" user "User.Drawings")
		(19 "Cmts.User" user "User.Comments")
		(21 "Eco1.User" user "User.Eco1")
		(23 "Eco2.User" user "User.Eco2")
		(25 "Edge.Cuts" user "Board Geometry/Outline")
		(27 "Margin" user)
		(31 "F.CrtYd" user "Package Geometry/Place Bound Top")
		(29 "B.CrtYd" user "Package Geometry/Place Bound Bottom")
		(35 "F.Fab" user "Ref Des/Assembly Top")
		(33 "B.Fab" user "Ref Des/Assembly Bottom")
	)
	(footprint ""
		(layer "B.Cu")
		(at 42.6974 -58.0136)
		(property "Reference" "C75"
			(at 0 0 0)
			(layer "B.SilkS")
			(hide yes)
			(effects
				(font
					(size 1.27 1.27)
				)
				(justify mirror)
			)
		)
		(property "Value" ""
			(at 0 0 0)
			(layer "B.Fab")
			(effects
				(font
					(size 1.27 1.27)
				)
				(justify mirror)
			)
		)
		(duplicate_pad_numbers_are_jumpers no)
		(fp_line
			(start -0.7874 -0.4064)
			(end -0.7874 0.4064)
			(stroke
				(width 0.1524)
				(type default)
			)
			(layer "B.SilkS")
		)
		(fp_line
			(start -0.7874 0.4064)
			(end 0.7874 0.4064)
			(stroke
				(width 0.1524)
				(type default)
			)
			(layer "B.SilkS")
		)
		(fp_line
			(start 0.7874 -0.4064)
			(end -0.7874 -0.4064)
			(stroke
				(width 0.1524)
				(type default)
			)
			(layer "B.SilkS")
		)
		(fp_line
			(start 0.7874 0.4064)
			(end 0.7874 -0.4064)
			(stroke
				(width 0.1524)
				(type default)
			)
			(layer "B.SilkS")
		)
		(fp_line
			(start -0.67945 -0.3048)
			(end -0.67945 0.3048)
			(stroke
				(width 0.1)
				(type default)
			)
			(layer "B.Fab")
		)
		(fp_line
			(start -0.67945 0.3048)
			(end -0.120396 0.3048)
			(stroke
				(width 0.1)
				(type default)
			)
			(layer "B.Fab")
		)
		(fp_line
			(start -0.12065 -0.3048)
			(end -0.67945 -0.3048)
			(stroke
				(width 0.1)
				(type default)
			)
			(layer "B.Fab")
		)
		(fp_line
			(start -0.12065 -0.2794)
			(end -0.12065 -0.3048)
			(stroke
				(width 0.1)
				(type default)
			)
			(layer "B.Fab")
		)
		(fp_line
			(start -0.120396 0.2794)
			(end 0.12065 0.2794)
			(stroke
				(width 0.1)
				(type default)
			)
			(layer "B.Fab")
		)
		(fp_line
			(start -0.120396 0.3048)
			(end -0.120396 0.2794)
			(stroke
				(width 0.1)
				(type default)
			)
			(layer "B.Fab")
		)
		(fp_line
			(start 0.12065 -0.305054)
			(end 0.12065 -0.2794)
			(stroke
				(width 0.1)
				(type default)
			)
			(layer "B.Fab")
		)
		(fp_line
			(start 0.12065 -0.2794)
			(end -0.12065 -0.2794)
			(stroke
				(width 0.1)
				(type default)
			)
			(layer "B.Fab")
		)
		(fp_line
			(start 0.12065 0.2794)
			(end 0.12065 0.3048)
			(stroke
				(width 0.1)
				(type default)
			)
			(layer "B.Fab")
		)
		(fp_line
			(start 0.12065 0.3048)
			(end 0.67945 0.3048)
			(stroke
				(width 0.1)
				(type default)
			)
			(layer "B.Fab")
		)
		(fp_line
			(start 0.67945 -0.305054)
			(end 0.12065 -0.305054)
			(stroke
				(width 0.1)
				(type default)
			)
			(layer "B.Fab")
		)
		(fp_line
			(start 0.67945 0.3048)
			(end 0.67945 -0.305054)
			(stroke
				(width 0.1)
				(type default)
			)
			(layer "B.Fab")
		)
		(pad "1" smd circle
			(at 0.40005 0 180)
			(size 0 0)
			(layers "B.Cu" "B.Mask" "B.Paste")
			(net "A_BMC_ADCAV33")
		)
		(pad "2" smd circle
			(at -0.40005 0 180)
			(size 0 0)
			(layers "B.Cu" "B.Mask" "B.Paste")
			(net "GND")
		)
	)
	(footprint ""
		(layer "B.Cu")
		(at 50.66411 -47.625 -90)
		(property "Reference" "C98"
			(at 0 0 90)
			(layer "B.SilkS")
			(hide yes)
			(effects
				(font
					(size 1.27 1.27)
				)
				(justify mirror)
			)
		)
		(property "Value" ""
			(at 0 0 90)
			(layer "B.Fab")
			(effects
				(font
					(size 1.27 1.27)
				)
				(justify mirror)
			)
		)
		(duplicate_pad_numbers_are_jumpers no)
		(fp_line
			(start -0.7874 0.4064)
			(end 0.7874 0.4064)
			(stroke
				(width 0.1524)
				(type default)
			)
			(layer "B.SilkS")
		)
		(fp_line
			(start 0.7874 0.4064)
			(end 0.7874 -0.4064)
			(stroke
				(width 0.1524)
				(type default)
			)
			(layer "B.SilkS")
		)
		(fp_line
			(start -0.7874 -0.4064)
			(end -0.7874 0.4064)
			(stroke
				(width 0.1524)
				(type default)
			)
			(layer "B.SilkS")
		)
		(fp_line
			(start 0.7874 -0.4064)
			(end -0.7874 -0.4064)
			(stroke
				(width 0.1524)
				(type default)
			)
			(layer "B.SilkS")
		)
		(fp_line
			(start -0.67945 0.3048)
			(end -0.120396 0.3048)
			(stroke
				(width 0.1)
				(type default)
			)
			(layer "B.Fab")
		)
		(fp_line
			(start -0.120396 0.3048)
			(end -0.120396 0.2794)
			(stroke
				(width 0.1)
				(type default)
			)
			(layer "B.Fab")
		)
		(fp_line
			(start 0.12065 0.3048)
			(end 0.67945 0.3048)
			(stroke
				(width 0.1)
				(type default)
			)
			(layer "B.Fab")
		)
		(fp_line
			(start 0.67945 0.3048)
			(end 0.67945 -0.305054)
			(stroke
				(width 0.1)
				(type default)
			)
			(layer "B.Fab")
		)
		(fp_line
			(start -0.120396 0.2794)
			(end 0.12065 0.2794)
			(stroke
				(width 0.1)
				(type default)
			)
			(layer "B.Fab")
		)
		(fp_line
			(start 0.12065 0.2794)
			(end 0.12065 0.3048)
			(stroke
				(width 0.1)
				(type default)
			)
			(layer "B.Fab")
		)
		(fp_line
			(start -0.12065 -0.2794)
			(end -0.12065 -0.3048)
			(stroke
				(width 0.1)
				(type default)
			)
			(layer "B.Fab")
		)
		(fp_line
			(start 0.12065 -0.2794)
			(end -0.12065 -0.2794)
			(stroke
				(width 0.1)
				(type default)
			)
			(layer "B.Fab")
		)
		(fp_line
			(start -0.67945 -0.3048)
			(end -0.67945 0.3048)
			(stroke
				(width 0.1)
				(type default)
			)
			(layer "B.Fab")
		)
		(fp_line
			(start -0.12065 -0.3048)
			(end -0.67945 -0.3048)
			(stroke
				(width 0.1)
				(type default)
			)
			(layer "B.Fab")
		)
		(fp_line
			(start 0.12065 -0.305054)
			(end 0.12065 -0.2794)
			(stroke
				(width 0.1)
				(type default)
			)
			(layer "B.Fab")
		)
		(fp_line
			(start 0.67945 -0.305054)
			(end 0.12065 -0.305054)
			(stroke
				(width 0.1)
				(type default)
			)
			(layer "B.Fab")
		)
		(pad "1" smd circle
			(at 0.40005 0 90)
			(size 0 0)
			(layers "B.Cu" "B.Mask" "B.Paste")
			(net "P1V2_AUX")
		)
		(pad "2" smd circle
			(at -0.40005 0 90)
			(size 0 0)
			(layers "B.Cu" "B.Mask" "B.Paste")
			(net "GND")
		)
	)
	(footprint ""
		(layer "B.Cu")
		(at 16.564864 -58.7502 -90)
		(property "Reference" "R135"
			(at 0 0 90)
			(layer "B.SilkS")
			(hide yes)
			(effects
				(font
					(size 1.27 1.27)
				)
				(justify mirror)
			)
		)
		(property "Value" ""
			(at 0 0 90)
			(layer "B.Fab")
			(effects
				(font
					(size 1.27 1.27)
				)
				(justify mirror)
			)
		)
		(duplicate_pad_numbers_are_jumpers no)
		(fp_line
			(start -0.7874 0.4064)
			(end 0.7874 0.4064)
			(stroke
				(width 0.1524)
				(type default)
			)
			(layer "B.SilkS")
		)
		(fp_line
			(start 0.7874 0.4064)
			(end 0.7874 -0.4064)
			(stroke
				(width 0.1524)
				(type default)
			)
			(layer "B.SilkS")
		)
		(fp_line
			(start -0.7874 -0.4064)
			(end -0.7874 0.4064)
			(stroke
				(width 0.1524)
				(type default)
			)
			(layer "B.SilkS")
		)
		(fp_line
			(start 0.7874 -0.4064)
			(end -0.7874 -0.4064)
			(stroke
				(width 0.1524)
				(type default)
			)
			(layer "B.SilkS")
		)
		(fp_line
			(start -0.67945 0.3048)
			(end -0.120396 0.3048)
			(stroke
				(width 0.1)
				(type default)
			)
			(layer "B.Fab")
		)
		(fp_line
			(start -0.120396 0.3048)
			(end -0.120396 0.2794)
			(stroke
				(width 0.1)
				(type default)
			)
			(layer "B.Fab")
		)
		(fp_line
			(start 0.12065 0.3048)
			(end 0.67945 0.3048)
			(stroke
				(width 0.1)
				(type default)
			)
			(layer "B.Fab")
		)
		(fp_line
			(start 0.67945 0.3048)
			(end 0.67945 -0.305054)
			(stroke
				(width 0.1)
				(type default)
			)
			(layer "B.Fab")
		)
		(fp_line
			(start -0.120396 0.2794)
			(end 0.12065 0.2794)
			(stroke
				(width 0.1)
				(type default)
			)
			(layer "B.Fab")
		)
		(fp_line
			(start 0.12065 0.2794)
			(end 0.12065 0.3048)
			(stroke
				(width 0.1)
				(type default)
			)
			(layer "B.Fab")
		)
		(fp_line
			(start -0.12065 -0.2794)
			(end -0.12065 -0.3048)
			(stroke
				(width 0.1)
				(type default)
			)
			(layer "B.Fab")
		)
		(fp_line
			(start 0.12065 -0.2794)
			(end -0.12065 -0.2794)
			(stroke
				(width 0.1)
				(type default)
			)
			(layer "B.Fab")
		)
		(fp_line
			(start -0.67945 -0.3048)
			(end -0.67945 0.3048)
			(stroke
				(width 0.1)
				(type default)
			)
			(layer "B.Fab")
		)
		(fp_line
			(start -0.12065 -0.3048)
			(end -0.67945 -0.3048)
			(stroke
				(width 0.1)
				(type default)
			)
			(layer "B.Fab")
		)
		(fp_line
			(start 0.12065 -0.305054)
			(end 0.12065 -0.2794)
			(stroke
				(width 0.1)
				(type default)
			)
			(layer "B.Fab")
		)
		(fp_line
			(start 0.67945 -0.305054)
			(end 0.12065 -0.305054)
			(stroke
				(width 0.1)
				(type default)
			)
			(layer "B.Fab")
		)
		(pad "1" smd circle
			(at 0.40005 0 90)
			(size 0 0)
			(layers "B.Cu" "B.Mask" "B.Paste")
			(net "SMB_BMC_MM15_SCL")
		)
		(pad "2" smd circle
			(at -0.40005 0 90)
			(size 0 0)
			(layers "B.Cu" "B.Mask" "B.Paste")
			(net "SMB_BMC_MM15_R1_SCL")
		)
	)
	(footprint ""
		(layer "B.Cu")
		(at 11.9126 -25.9842 180)
		(property "Reference" "R104"
			(at 0 0 0)
			(layer "B.SilkS")
			(hide yes)
			(effects
				(font
					(size 1.27 1.27)
				)
				(justify mirror)
			)
		)
		(property "Value" ""
			(at 0 0 0)
			(layer "B.Fab")
			(effects
				(font
					(size 1.27 1.27)
				)
				(justify mirror)
			)
		)
		(duplicate_pad_numbers_are_jumpers no)
		(fp_line
			(start 0.7874 0.4064)
			(end 0.7874 -0.4064)
			(stroke
				(width 0.1524)
				(type default)
			)
			(layer "B.SilkS")
		)
		(fp_line
			(start 0.7874 -0.4064)
			(end -0.7874 -0.4064)
			(stroke
				(width 0.1524)
				(type default)
			)
			(layer "B.SilkS")
		)
		(fp_line
			(start -0.7874 0.4064)
			(end 0.7874 0.4064)
			(stroke
				(width 0.1524)
				(type default)
			)
			(layer "B.SilkS")
		)
		(fp_line
			(start -0.7874 -0.4064)
			(end -0.7874 0.4064)
			(stroke
				(width 0.1524)
				(type default)
			)
			(layer "B.SilkS")
		)
		(fp_line
			(start 0.67945 0.3048)
			(end 0.67945 -0.305054)
			(stroke
				(width 0.1)
				(type default)
			)
			(layer "B.Fab")
		)
		(fp_line
			(start 0.67945 -0.305054)
			(end 0.12065 -0.305054)
			(stroke
				(width 0.1)
				(type default)
			)
			(layer "B.Fab")
		)
		(fp_line
			(start 0.12065 0.3048)
			(end 0.67945 0.3048)
			(stroke
				(width 0.1)
				(type default)
			)
			(layer "B.Fab")
		)
		(fp_line
			(start 0.12065 0.2794)
			(end 0.12065 0.3048)
			(stroke
				(width 0.1)
				(type default)
			)
			(layer "B.Fab")
		)
		(fp_line
			(start 0.12065 -0.2794)
			(end -0.12065 -0.2794)
			(stroke
				(width 0.1)
				(type default)
			)
			(layer "B.Fab")
		)
		(fp_line
			(start 0.12065 -0.305054)
			(end 0.12065 -0.2794)
			(stroke
				(width 0.1)
				(type default)
			)
			(layer "B.Fab")
		)
		(fp_line
			(start -0.120396 0.3048)
			(end -0.120396 0.2794)
			(stroke
				(width 0.1)
				(type default)
			)
			(layer "B.Fab")
		)
		(fp_line
			(start -0.120396 0.2794)
			(end 0.12065 0.2794)
			(stroke
				(width 0.1)
				(type default)
			)
			(layer "B.Fab")
		)
		(fp_line
			(start -0.12065 -0.2794)
			(end -0.12065 -0.3048)
			(stroke
				(width 0.1)
				(type default)
			)
			(layer "B.Fab")
		)
		(fp_line
			(start -0.12065 -0.3048)
			(end -0.67945 -0.3048)
			(stroke
				(width 0.1)
				(type default)
			)
			(layer "B.Fab")
		)
		(fp_line
			(start -0.67945 0.3048)
			(end -0.120396 0.3048)
			(stroke
				(width 0.1)
				(type default)
			)
			(layer "B.Fab")
		)
		(fp_line
			(start -0.67945 -0.3048)
			(end -0.67945 0.3048)
			(stroke
				(width 0.1)
				(type default)
			)
			(layer "B.Fab")
		)
		(pad "1" smd circle
			(at 0.40005 0)
			(size 0 0)
			(layers "B.Cu" "B.Mask" "B.Paste")
			(net "UART_BMC_5_RXD_BUF_R")
		)
		(pad "2" smd circle
			(at -0.40005 0)
			(size 0 0)
			(layers "B.Cu" "B.Mask" "B.Paste")
			(net "UART_BMC_5_RXD_BUF1")
		)
	)
	(footprint ""
		(layer "B.Cu")
		(at 62.23 -21.082 -90)
		(property "Reference" "U36"
			(at 0.0254 -1.87833 270)
			(unlocked yes)
			(layer "B.SilkS")
			(effects
				(font
					(size 0.7874 0.5842)
					(thickness 0.1524)
				)
				(justify left mirror)
			)
		)
		(property "Value" ""
			(at 0 0 90)
			(layer "B.Fab")
			(effects
				(font
					(size 1.27 1.27)
				)
				(justify mirror)
			)
		)
		(duplicate_pad_numbers_are_jumpers no)
		(fp_line
			(start -1.3462 1.1938)
			(end -1.3462 -1.1938)
			(stroke
				(width 0.1524)
				(type default)
			)
			(layer "B.SilkS")
		)
		(fp_line
			(start 1.3462 1.1938)
			(end -1.3462 1.1938)
			(stroke
				(width 0.1524)
				(type default)
			)
			(layer "B.SilkS")
		)
		(fp_line
			(start -1.3462 -1.1938)
			(end 1.3462 -1.1938)
			(stroke
				(width 0.1524)
				(type default)
			)
			(layer "B.SilkS")
		)
		(fp_line
			(start 1.3462 -1.1938)
			(end 1.3462 1.1684)
			(stroke
				(width 0.1524)
				(type default)
			)
			(layer "B.SilkS")
		)
		(fp_poly
			(pts
				(xy 1.447038 -0.760476) (xy 2.052066 -0.457962) (xy 2.052066 -1.06299)
			)
			(stroke
				(width 0)
				(type default)
			)
			(fill yes)
			(layer "B.SilkS")
		)
		(fp_line
			(start -0.674878 1.124966)
			(end -0.674878 -1.124966)
			(stroke
				(width 0.1)
				(type default)
			)
			(layer "B.Fab")
		)
		(fp_line
			(start 0.674878 1.124966)
			(end -0.674878 1.124966)
			(stroke
				(width 0.1)
				(type default)
			)
			(layer "B.Fab")
		)
		(fp_line
			(start -0.674878 -1.124966)
			(end 0.674878 -1.124966)
			(stroke
				(width 0.1)
				(type default)
			)
			(layer "B.Fab")
		)
		(fp_line
			(start 0.674878 -1.124966)
			(end 0.674878 1.124966)
			(stroke
				(width 0.1)
				(type default)
			)
			(layer "B.Fab")
		)
		(fp_poly
			(pts
				(xy 1.447038 -0.760476) (xy 2.052066 -0.457962) (xy 2.052066 -1.06299)
			)
			(stroke
				(width 0)
				(type default)
			)
			(fill yes)
			(layer "B.Fab")
		)
		(pad "1" smd rect
			(at 0.899922 -0.750062 90)
			(size 0.6096 0.6096)
			(layers "B.Cu" "B.Mask" "B.Paste")
			(net "DEBUG_PORT_PRSNT")
		)
		(pad "2" smd rect
			(at 0.899922 0)
			(size 0.4064 0.6096)
			(layers "B.Cu" "B.Mask" "B.Paste")
			(net "DEBUG_PORT_UART_RX")
		)
		(pad "3" smd rect
			(at 0.899922 0.750062 90)
			(size 0.6096 0.6096)
			(layers "B.Cu" "B.Mask" "B.Paste")
			(net "GND")
		)
		(pad "4" smd rect
			(at -0.899922 0.750062 90)
			(size 0.6096 0.6096)
			(layers "B.Cu" "B.Mask" "B.Paste")
			(net "SPA_SIN_SW_DBG")
		)
		(pad "5" smd rect
			(at -0.899922 -0.750062 90)
			(size 0.6096 0.6096)
			(layers "B.Cu" "B.Mask" "B.Paste")
			(net "P3V3_AUX")
		)
	)
	(footprint ""
		(layer "B.Cu")
		(at 61.423804 -34.637726 -90)
		(property "Reference" "R237"
			(at 0 0 90)
			(layer "B.SilkS")
			(hide yes)
			(effects
				(font
					(size 1.27 1.27)
				)
				(justify mirror)
			)
		)
		(property "Value" ""
			(at 0 0 90)
			(layer "B.Fab")
			(effects
				(font
					(size 1.27 1.27)
				)
				(justify mirror)
			)
		)
		(duplicate_pad_numbers_are_jumpers no)
		(fp_line
			(start -0.7874 0.4064)
			(end 0.7874 0.4064)
			(stroke
				(width 0.1524)
				(type default)
			)
			(layer "B.SilkS")
		)
		(fp_line
			(start 0.7874 0.4064)
			(end 0.7874 -0.4064)
			(stroke
				(width 0.1524)
				(type default)
			)
			(layer "B.SilkS")
		)
		(fp_line
			(start -0.7874 -0.4064)
			(end -0.7874 0.4064)
			(stroke
				(width 0.1524)
				(type default)
			)
			(layer "B.SilkS")
		)
		(fp_line
			(start 0.7874 -0.4064)
			(end -0.7874 -0.4064)
			(stroke
				(width 0.1524)
				(type default)
			)
			(layer "B.SilkS")
		)
		(fp_line
			(start -0.67945 0.3048)
			(end -0.120396 0.3048)
			(stroke
				(width 0.1)
				(type default)
			)
			(layer "B.Fab")
		)
		(fp_line
			(start -0.120396 0.3048)
			(end -0.120396 0.2794)
			(stroke
				(width 0.1)
				(type default)
			)
			(layer "B.Fab")
		)
		(fp_line
			(start 0.12065 0.3048)
			(end 0.67945 0.3048)
			(stroke
				(width 0.1)
				(type default)
			)
			(layer "B.Fab")
		)
		(fp_line
			(start 0.67945 0.3048)
			(end 0.67945 -0.305054)
			(stroke
				(width 0.1)
				(type default)
			)
			(layer "B.Fab")
		)
		(fp_line
			(start -0.120396 0.2794)
			(end 0.12065 0.2794)
			(stroke
				(width 0.1)
				(type default)
			)
			(layer "B.Fab")
		)
		(fp_line
			(start 0.12065 0.2794)
			(end 0.12065 0.3048)
			(stroke
				(width 0.1)
				(type default)
			)
			(layer "B.Fab")
		)
		(fp_line
			(start -0.12065 -0.2794)
			(end -0.12065 -0.3048)
			(stroke
				(width 0.1)
				(type default)
			)
			(layer "B.Fab")
		)
		(fp_line
			(start 0.12065 -0.2794)
			(end -0.12065 -0.2794)
			(stroke
				(width 0.1)
				(type default)
			)
			(layer "B.Fab")
		)
		(fp_line
			(start -0.67945 -0.3048)
			(end -0.67945 0.3048)
			(stroke
				(width 0.1)
				(type default)
			)
			(layer "B.Fab")
		)
		(fp_line
			(start -0.12065 -0.3048)
			(end -0.67945 -0.3048)
			(stroke
				(width 0.1)
				(type default)
			)
			(layer "B.Fab")
		)
		(fp_line
			(start 0.12065 -0.305054)
			(end 0.12065 -0.2794)
			(stroke
				(width 0.1)
				(type default)
			)
			(layer "B.Fab")
		)
		(fp_line
			(start 0.67945 -0.305054)
			(end 0.12065 -0.305054)
			(stroke
				(width 0.1)
				(type default)
			)
			(layer "B.Fab")
		)
		(pad "1" smd circle
			(at 0.40005 0 90)
			(size 0 0)
			(layers "B.Cu" "B.Mask" "B.Paste")
			(net "FM_DBP_BMC_PRDY_N")
		)
		(pad "2" smd circle
			(at -0.40005 0 90)
			(size 0 0)
			(layers "B.Cu" "B.Mask" "B.Paste")
			(net "FM_DBP_BMC_PRDY_R_N")
		)
	)
)
